FILE_TYPE = CONNECTIVITY;
{Allegro Design Entry HDL 17.4-2019 S026 (4007227) 1/17/2022}
"PAGE_NUMBER" = 477;
0"NC";
1"GND\g";
2"GND\g";
3"GND\g";
4"GND\g";
5"P3V3_AUX\g";
6"GND\g";
7"GND\g";
8"GND\g";
9"GND\g";
10"GND\g";
11"GND\g";
12"GND\g";
13"GND\g";
14"GND\g";
15"GND\g";
16"GND\g";
17"P3V3_AUX\g";
18"GND\g";
19"P3V3_AUX\g";
20"GND\g";
21"P0V9_RETIMER_CPU1_IMON2";
22"P0V9_RETIMER_CPU1_EN1_R";
23"P0V9_RETIMER_CPU1_INALERT";
24"NC_P0V9_RETIMER_CPU1_IMON5";
25"NC_P0V9_RETIMER_CPU1_IMON4";
26"NC_P0V9_RETIMER_CPU1_PWM3";
27"P0V9_RETIMER_CPU1_PWM1";
28"P1V8_AUX\g";
29"P3V3_AUX\g";
30"GND\g";
31"P12V_AUX\g";
32"GND\g";
33"P5V_AUX\g";
34"GND\g";
35"GND\g";
36"GND\g";
37"GND\g";
38"P3V3_AUX\g";
39"P0V9_CPU1_RT_2D\g";
40"P0V9_CPU1_RT_2D\g";
41"P0V9_RETIMER_CPU1_IMON1";
42"P0V9_RETIMER_CPU1_PMSDA_R";
43"TP_P0V9_RETIMER_CPU1_PMALERT";
44"P0V9_RETIMER_CPU1_VCC";
45"P0V9_RETIMER_CPU1_PMSCL_R";
46"P0V9_RETIMER_CPU1_SVID_SDA";
47"TP_P0V9_RETIMER_CPU1_SVID_ALERT_N";
48"P0V9_RETIMER_CPU1_VRHOT";
49"NC_P0V9_RETIMER_CPU1_IMON3";
50"NC_P0V9_RETIMER_CPU1_PG1";
51"P0V9_RETIMER_CPU1_SVID_CLK";
52"P0V9_RETIMER_CPU1_EN0_R";
53"P0V9_RETIMER_CPU1_SENSE_SH_N";
54"NC_P0V9_RETIMER_CPU1_PWM4";
55"P0V9_RETIMER_CPU1_SENSE_R_P";
56"NC_P0V9_RETIMER_CPU1_PWM7";
57"PWRGD_P0V9_RETIMER_CPU1_R";
58"P0V9_RETIMER_CPU1_PWM2";
59"PV09_RETIMER_CPU1_VCCS";
60"P0V9_RETIMER_CPU1_VMON";
61"P0V9_RETIMER_CPU1_VINSEN";
62"P0V9_RETIMER_CPU1_TEMP1_R";
63"NC_P0V9_RETIMER_CPU1_IMON7";
64"NC_P0V9_RETIMER_CPU1_PWM5";
65"NC_P0V9_RETIMER_CPU1_PWM6";
66"NC_P0V9_RETIMER_CPU1_IMON6";
67"P0V9_RETIMER_CPU1_CFP";
68"P0V9_RETIMER_CPU1_ADDR";
69"P0V9_RETIMER_CPU1_TEMP0";
70"NC_P0V9_RETIMER_CPU1_PWM8";
71"NC_P0V9_RETIMER_CPU1_IMON8";
72"TP_P0V9_RETIMER_CPU1_VRHOT";
73"P0V9_RETIMER_CPU1_PMSCL";
74"P0V9_RETIMER_CPU1_EN";
75"PWRGD_P0V9_RETIMER_CPU1";
76"P0V9_RETIMER_CPU1_PMSDA";
77"P0V9_RETIMER_CPU1_SENSE_SH_P";
%"UNIVERSAL_GND"
"1","(-7875,1775)","5","pure_quanta_power","I1";
;
CDS_LIB"pure_quanta_power"
HDL_POWER"GND";
"A"1;
%"Q_RES"
"1","(-6300,725)","0","pure_quanta","I10";
;
LOCATION"PR6809"
$SEC"1"
CDS_SEC"1"
VALUE"0"
TOLERANCE"5%"
PACK_TYPE"0402LF"
WATTAGE"1/16W"
MATERIAL"CHIP"
CDS_LIB"pure_quanta"
PART_NUMBER"CS00002JB13";
"B"
$PN"2"61;
"A"
$PN"1"31;
%"Q_RES"
"1","(-6300,825)","0","pure_quanta","I11";
;
LOCATION"PR6808"
$SEC"1"
CDS_SEC"1"
VALUE"0"
TOLERANCE"5%"
MATERIAL"EMPTY"
PACK_TYPE"0402LF"
WATTAGE"1/16W"
CDS_LIB"pure_quanta"
PART_NUMBER"CS00002JB13";
"B"
$PN"2"60;
"A"
$PN"1"31;
%"UNIVERSAL_GND"
"1","(-6100,975)","0","pure_quanta_power","I12";
;
CDS_LIB"pure_quanta_power"
HDL_POWER"GND";
"A"2;
%"Q_RES"
"1","(-5750,1075)","0","pure_quanta","I13";
;
LOCATION"PR6533"
$SEC"1"
CDS_SEC"1"
VALUE"22.1K"
TOLERANCE"1%"
CDS_LIB"pure_quanta"
PACK_TYPE"0402LF"
MATERIAL"CHIP"
WATTAGE"1/16W"
PART_NUMBER"CS32212FB02";
"B"
$PN"2"68;
"A"
$PN"1"2;
%"Q_RES"
"2","(-6300,2375)","2","pure_quanta","I14";
;
LOCATION"R665"
$SEC"1"
CDS_SEC"1"
WATTAGE"1/16W"
TOLERANCE"1%"
VALUE"1K"
MATERIAL"CHIP"
PACK_TYPE"0402LF"
CDS_LIB"pure_quanta"
PART_NUMBER"CS21002FB06";
"A"
$PN"1"38;
"B"
$PN"2"23;
%"Q_RES"
"2","(-5925,2375)","2","pure_quanta","I15";
;
LOCATION"R663"
$SEC"1"
CDS_SEC"1"
PACK_TYPE"0402LF"
WATTAGE"1/16W"
VALUE"1K"
TOLERANCE"1%"
MATERIAL"CHIP"
CDS_LIB"pure_quanta"
PART_NUMBER"CS21002FB06";
"A"
$PN"1"38;
"B"
$PN"2"67;
%"UNIVERSAL_GND"
"1","(-8050,3550)","0","pure_quanta_power","I16";
;
CDS_LIB"pure_quanta_power"
HDL_POWER"GND";
"A"3;
%"VCC15"
"1","(-8050,4475)","0","pure_quanta_power","I17";
;
HDL_POWER"P0V9_CPU1_RT_2D"
CDS_LIB"pure_quanta_power";
"A"40;
%"Q_RES"
"1","(-7350,1775)","0","pure_quanta","I2";
;
LOCATION"R6800"
$SEC"1"
CDS_SEC"1"
MATERIAL"CHIP"
WATTAGE"1/16W"
PACK_TYPE"0402LF"
TOLERANCE"5%"
VALUE"0"
CDS_LIB"pure_quanta"
PART_NUMBER"CS00002JB13";
"B"
$PN"2"22;
"A"
$PN"1"1;
%"Q_RES"
"1","(-7175,3650)","0","pure_quanta","I22";
;
LOCATION"PR6602"
$SEC"1"
CDS_SEC"1"
WATTAGE"1/16W"
MATERIAL"CHIP"
PACK_TYPE"0402LF"
TOLERANCE"1%"
VALUE"49.9"
CDS_LIB"pure_quanta"
PART_NUMBER"CS04992FB07";
"B"
$PN"2"4;
"A"
$PN"1"53;
%"Q_RES"
"1","(-7125,4325)","0","pure_quanta","I23";
;
LOCATION"PR6600"
$SEC"1"
CDS_SEC"1"
PACK_TYPE"0402LF"
TOLERANCE"1%"
VALUE"49.9"
MATERIAL"CHIP"
WATTAGE"1/16W"
CDS_LIB"pure_quanta"
PART_NUMBER"CS04992FB07";
"B"
$PN"2"39;
"A"
$PN"1"77;
%"UNIVERSAL_GND"
"1","(-6650,3550)","0","pure_quanta_power","I24";
;
CDS_LIB"pure_quanta_power"
HDL_POWER"GND";
"A"4;
%"VCC15"
"1","(-6625,4475)","0","pure_quanta_power","I25";
;
HDL_POWER"P0V9_CPU1_RT_2D"
CDS_LIB"pure_quanta_power";
"A"39;
%"VCC15"
"1","(-6300,2600)","0","pure_quanta_power","I26";
;
HDL_POWER"P3V3_AUX"
CDS_LIB"pure_quanta_power";
"A"38;
%"Q_RES"
"1","(-6100,4175)","0","pure_quanta","I27";
;
LOCATION"PR6601"
$SEC"1"
CDS_SEC"1"
VALUE"0"
TOLERANCE"5%"
MATERIAL"CHIP"
WATTAGE"1/16W"
PACK_TYPE"0402LF"
CDS_LIB"pure_quanta"
PART_NUMBER"CS00002JB13";
"B"
$PN"2"55;
"A"
$PN"1"77;
%"Q_CAP"
"1","(-5650,4000)","0","pure_quanta","I28";
;
LOCATION"PC6600"
$SEC"1"
CDS_SEC"1"
TOLERANCE"10%"
MATERIAL"X7R"
PACK_TYPE"0402"
VOLTAGE"50V"
VALUE"3300PF"
CDS_LIB"pure_quanta"
PART_NUMBER"TMP_QCH2336K1B12";
"B"
$PN"2"53;
"A"
$PN"1"55;
%"Q_RES"
"2","(-6000,400)","2","pure_quanta","I3";
;
LOCATION"PR6821"
$SEC"1"
CDS_SEC"1"
WATTAGE"1/16W"
MATERIAL"CHIP"
PACK_TYPE"0402LF"
VALUE"0"
TOLERANCE"5%"
CDS_LIB"pure_quanta"
PART_NUMBER"CS00002JB13";
"A"
$PN"1"60;
"B"
$PN"2"37;
%"Q_RES"
"1","(-6500,4875)","0","pure_quanta","I31";
;
LOCATION"R658"
$SEC"1"
CDS_SEC"1"
VALUE"0"
TOLERANCE"5%"
PACK_TYPE"0402LF"
WATTAGE"1/16W"
MATERIAL"CHIP"
CDS_LIB"pure_quanta"
PART_NUMBER"CS00002JB13";
"B"
$PN"2"42;
"A"
$PN"1"76;
%"Q_RES"
"1","(-6575,5425)","0","pure_quanta","I32";
;
LOCATION"PR6818"
$SEC"1"
CDS_SEC"1"
MATERIAL"EMPTY"
VALUE"1K"
TOLERANCE"1%"
WATTAGE"1/16W"
PACK_TYPE"0402LF"
CDS_LIB"pure_quanta"
PART_NUMBER"CS21002FB06";
"B"
$PN"2"47;
"A"
$PN"1"19;
%"Q_RES"
"1","(-6500,5025)","0","pure_quanta","I33";
;
LOCATION"R657"
$SEC"1"
CDS_SEC"1"
MATERIAL"CHIP"
PACK_TYPE"0402LF"
WATTAGE"1/16W"
VALUE"0"
TOLERANCE"5%"
CDS_LIB"pure_quanta"
PART_NUMBER"CS00002JB13";
"B"
$PN"2"45;
"A"
$PN"1"73;
%"VCC15"
"1","(-7075,5850)","0","pure_quanta_power","I34";
;
HDL_POWER"P3V3_AUX"
CDS_LIB"pure_quanta_power";
"A"19;
%"VCC15"
"1","(-6650,6450)","0","pure_quanta_power","I35";
;
HDL_POWER"P3V3_AUX"
CDS_LIB"pure_quanta_power";
"A"5;
%"Q_RES"
"1","(-6575,5575)","0","pure_quanta","I36";
;
LOCATION"PR6804"
$SEC"1"
CDS_SEC"1"
VALUE"1K"
TOLERANCE"1%"
MATERIAL"EMPTY"
WATTAGE"1/16W"
PACK_TYPE"0402LF"
CDS_LIB"pure_quanta"
PART_NUMBER"CS21002FB06";
"B"
$PN"2"46;
"A"
$PN"1"19;
%"Q_RES"
"1","(-6575,5725)","0","pure_quanta","I37";
;
LOCATION"PR6806"
$SEC"1"
CDS_SEC"1"
MATERIAL"EMPTY"
WATTAGE"1/16W"
PACK_TYPE"0402LF"
TOLERANCE"1%"
VALUE"1K"
CDS_LIB"pure_quanta"
PART_NUMBER"CS21002FB06";
"B"
$PN"2"51;
"A"
$PN"1"19;
%"Q_RES"
"1","(-6500,6025)","0","pure_quanta","I38";
;
LOCATION"R662"
$SEC"1"
CDS_SEC"1"
TOLERANCE"5%"
VALUE"0"
WATTAGE"1/16W"
MATERIAL"CHIP"
PACK_TYPE"0402LF"
CDS_LIB"pure_quanta"
PART_NUMBER"CS00002JB13";
"B"
$PN"2"52;
"A"
$PN"1"74;
%"Q_RES"
"1","(-7225,6175)","0","pure_quanta","I39";
;
LOCATION"R661"
$SEC"1"
CDS_SEC"1"
PACK_TYPE"0402LF"
WATTAGE"1/16W"
MATERIAL"CHIP"
VALUE"0"
TOLERANCE"5%"
CDS_LIB"pure_quanta"
PART_NUMBER"CS00002JB13";
"B"
$PN"2"57;
"A"
$PN"1"75;
%"UNIVERSAL_GND"
"1","(-5875,100)","0","pure_quanta_power","I4";
;
CDS_LIB"pure_quanta_power"
HDL_POWER"GND";
"A"37;
%"UNIVERSAL_GND"
"1","(-6350,5100)","5","pure_quanta_power","I41";
;
CDS_LIB"pure_quanta_power"
HDL_POWER"GND";
"A"36;
%"Q_RES"
"2","(-6200,5250)","0","pure_quanta","I42";
;
LOCATION"PR6811"
$SEC"1"
CDS_SEC"1"
MATERIAL"CHIP"
PACK_TYPE"0402LF"
VALUE"0"
TOLERANCE"5%"
WATTAGE"1/16W"
CDS_LIB"pure_quanta"
PART_NUMBER"CS00002JB13";
"A"
$PN"1"51;
"B"
$PN"2"36;
%"Q_RES"
"2","(-5850,5250)","0","pure_quanta","I43";
;
LOCATION"PR6820"
$SEC"1"
CDS_SEC"1"
WATTAGE"1/16W"
TOLERANCE"5%"
PACK_TYPE"0402LF"
VALUE"0"
MATERIAL"CHIP"
CDS_LIB"pure_quanta"
PART_NUMBER"CS00002JB13";
"A"
$PN"1"46;
"B"
$PN"2"36;
%"Q_RES"
"2","(-5500,5250)","0","pure_quanta","I44";
;
LOCATION"PR6802"
$SEC"1"
CDS_SEC"1"
VALUE"0"
TOLERANCE"5%"
MATERIAL"EMPTY"
PACK_TYPE"0402LF"
WATTAGE"1/16W"
CDS_LIB"pure_quanta"
PART_NUMBER"CS00002JB13";
"A"
$PN"1"47;
"B"
$PN"2"36;
%"Q_CAP"
"2","(-5650,6325)","0","pure_quanta","I45";
;
LOCATION"C107"
$SEC"1"
CDS_SEC"1"
MATERIAL"EMPTY"
VALUE"1000PF"
VOLTAGE"50V"
TOLERANCE"5%"
PACK_TYPE"0402"
CDS_LIB"pure_quanta"
PART_NUMBER"TMP_QCH21006JB10";
"A"
$PN"1"57;
"B"
$PN"2"12;
%"Q_RES"
"2","(-5250,400)","2","pure_quanta","I46";
;
LOCATION"PR6813"
$SEC"1"
CDS_SEC"1"
WATTAGE"1/16W"
VALUE"1K"
TOLERANCE"1%"
MATERIAL"EMPTY"
PACK_TYPE"0402LF"
CDS_LIB"pure_quanta"
PART_NUMBER"CS21002FB06";
"A"
$PN"1"61;
"B"
$PN"2"35;
%"UNIVERSAL_GND"
"1","(-5125,100)","0","pure_quanta_power","I47";
;
CDS_LIB"pure_quanta_power"
HDL_POWER"GND";
"A"35;
%"Q_CAP"
"1","(-5125,400)","0","pure_quanta","I48";
;
LOCATION"PC819"
$SEC"1"
CDS_SEC"1"
MATERIAL"X7R"
PACK_TYPE"0402"
TOLERANCE"10%"
VOLTAGE"25V"
VALUE"0.1UF"
CDS_LIB"pure_quanta"
PART_NUMBER"CH4104K1B00";
"B"
$PN"2"35;
"A"
$PN"1"61;
%"UNIVERSAL_GND"
"1","(-4900,500)","0","pure_quanta_power","I49";
;
CDS_LIB"pure_quanta_power"
HDL_POWER"GND";
"A"34;
%"Q_CAP"
"1","(-5875,400)","0","pure_quanta","I5";
;
LOCATION"PC514"
$SEC"1"
CDS_SEC"1"
TOLERANCE"10%"
VALUE"0.1UF"
VOLTAGE"25V"
PACK_TYPE"0402"
MATERIAL"EMPTY"
CDS_LIB"pure_quanta"
PART_NUMBER"CH4104K1B00";
"B"
$PN"2"37;
"A"
$PN"1"60;
%"UNIVERSAL_GND"
"1","(-2500,550)","0","pure_quanta_power","I50";
;
CDS_LIB"pure_quanta_power"
HDL_POWER"GND";
"A"6;
%"Q_CAP"
"1","(-2500,775)","0","pure_quanta","I51";
;
LOCATION"PC523"
$SEC"1"
CDS_SEC"1"
TOLERANCE"10%"
PACK_TYPE"0402"
VALUE"470PF"
VOLTAGE"50V"
MATERIAL"X7R"
CDS_LIB"pure_quanta"
PART_NUMBER"TMP_QCH14706KB18";
"B"
$PN"2"6;
"A"
$PN"1"69;
%"Q_RES"
"1","(-2125,1275)","0","pure_quanta","I52";
;
LOCATION"PR6548"
$SEC"1"
CDS_SEC"1"
WATTAGE"1/16W"
MATERIAL"CHIP"
TOLERANCE"5%"
VALUE"0"
PACK_TYPE"0402LF"
CDS_LIB"pure_quanta"
PART_NUMBER"CS00002JB13";
"B"
$PN"2"8;
"A"
$PN"1"62;
%"UNIVERSAL_GND"
"1","(-1800,525)","0","pure_quanta_power","I53";
;
CDS_LIB"pure_quanta_power"
HDL_POWER"GND";
"A"7;
%"Q_RES"
"2","(-1800,775)","0","pure_quanta","I54";
;
LOCATION"PR6815"
$SEC"1"
CDS_SEC"1"
VALUE"10K"
PACK_TYPE"0402LF"
TOLERANCE"1%"
MATERIAL"EMPTY"
WATTAGE"1/16W"
CDS_LIB"pure_quanta"
PART_NUMBER"CS31002FB08";
"A"
$PN"1"69;
"B"
$PN"2"7;
%"UNIVERSAL_GND"
"1","(-1750,1150)","0","pure_quanta_power","I55";
;
CDS_LIB"pure_quanta_power"
HDL_POWER"GND";
"A"8;
%"Q_RES"
"1","(-1975,1675)","0","pure_quanta","I56";
;
LOCATION"PR6816"
$SEC"1"
CDS_SEC"1"
MATERIAL"CHIP"
PACK_TYPE"0402LF"
VALUE"0"
TOLERANCE"5%"
WATTAGE"1/16W"
CDS_LIB"pure_quanta"
PART_NUMBER"CS00002JB13";
"B"
$PN"2"72;
"A"
$PN"1"48;
%"Q_RES"
"1","(-2125,1925)","0","pure_quanta","I57";
;
LOCATION"PR6544"
$SEC"1"
CDS_SEC"1"
WATTAGE"1/16W"
MATERIAL"CHIP"
TOLERANCE"5%"
VALUE"0"
PACK_TYPE"0402LF"
CDS_LIB"pure_quanta"
PART_NUMBER"CS00002JB13";
"B"
$PN"2"9;
"A"
$PN"1"71;
%"Q_RES"
"1","(-2125,2375)","0","pure_quanta","I58";
;
LOCATION"PR6543"
$SEC"1"
CDS_SEC"1"
MATERIAL"CHIP"
WATTAGE"1/16W"
VALUE"0"
TOLERANCE"5%"
PACK_TYPE"0402LF"
CDS_LIB"pure_quanta"
PART_NUMBER"CS00002JB13";
"B"
$PN"2"10;
"A"
$PN"1"63;
%"UNIVERSAL_GND"
"1","(-1750,1775)","0","pure_quanta_power","I59";
;
CDS_LIB"pure_quanta_power"
HDL_POWER"GND";
"A"9;
%"VCC15"
"1","(-7000,750)","0","pure_quanta_power","I6";
;
HDL_POWER"P5V_AUX"
CDS_LIB"pure_quanta_power";
"A"33;
%"UNIVERSAL_GND"
"1","(-1750,2150)","0","pure_quanta_power","I60";
;
CDS_LIB"pure_quanta_power"
HDL_POWER"GND";
"A"10;
%"UNIVERSAL_GND"
"1","(-5000,2650)","0","pure_quanta_power","I61";
;
CDS_LIB"pure_quanta_power"
HDL_POWER"GND";
"A"32;
%"UNIVERSAL_GND"
"1","(-5000,2875)","0","pure_quanta_power","I62";
;
CDS_LIB"pure_quanta_power"
HDL_POWER"GND";
"A"11;
%"UNIVERSAL_GND"
"1","(-4950,6325)","1","pure_quanta_power","I63";
;
CDS_LIB"pure_quanta_power"
HDL_POWER"GND";
"A"12;
%"Q_RES"
"1","(-2125,2825)","0","pure_quanta","I64";
;
LOCATION"PR6542"
$SEC"1"
CDS_SEC"1"
MATERIAL"CHIP"
WATTAGE"1/16W"
TOLERANCE"5%"
VALUE"0"
PACK_TYPE"0402LF"
CDS_LIB"pure_quanta"
PART_NUMBER"CS00002JB13";
"B"
$PN"2"13;
"A"
$PN"1"66;
%"Q_RES"
"1","(-2125,3275)","0","pure_quanta","I65";
;
LOCATION"PR6541"
$SEC"1"
CDS_SEC"1"
WATTAGE"1/16W"
MATERIAL"CHIP"
TOLERANCE"5%"
VALUE"0"
PACK_TYPE"0402LF"
CDS_LIB"pure_quanta"
PART_NUMBER"CS00002JB13";
"B"
$PN"2"14;
"A"
$PN"1"24;
%"UNIVERSAL_GND"
"1","(-1750,2575)","0","pure_quanta_power","I66";
;
CDS_LIB"pure_quanta_power"
HDL_POWER"GND";
"A"13;
%"UNIVERSAL_GND"
"1","(-1750,3025)","0","pure_quanta_power","I67";
;
CDS_LIB"pure_quanta_power"
HDL_POWER"GND";
"A"14;
%"Q_RES"
"1","(-2125,3725)","0","pure_quanta","I68";
;
LOCATION"PR6540"
$SEC"1"
CDS_SEC"1"
WATTAGE"1/16W"
VALUE"0"
TOLERANCE"5%"
MATERIAL"CHIP"
PACK_TYPE"0402LF"
CDS_LIB"pure_quanta"
PART_NUMBER"CS00002JB13";
"B"
$PN"2"15;
"A"
$PN"1"25;
%"Q_RES"
"1","(-2125,4175)","0","pure_quanta","I69";
;
LOCATION"PR6539"
$SEC"1"
CDS_SEC"1"
MATERIAL"CHIP"
WATTAGE"1/16W"
TOLERANCE"5%"
VALUE"0"
PACK_TYPE"0402LF"
CDS_LIB"pure_quanta"
PART_NUMBER"CS00002JB13";
"B"
$PN"2"16;
"A"
$PN"1"49;
%"Q_RES"
"1","(-6700,600)","0","pure_quanta","I7";
;
LOCATION"PR885"
$SEC"1"
CDS_SEC"1"
MATERIAL"EMPTY"
VALUE"5.36K"
WATTAGE"1/16W"
TOLERANCE"1%"
PACK_TYPE"0402LF"
CDS_LIB"pure_quanta"
PART_NUMBER"CS25362FB02";
"B"
$PN"2"60;
"A"
$PN"1"33;
%"UNIVERSAL_GND"
"1","(-1750,3525)","0","pure_quanta_power","I70";
;
CDS_LIB"pure_quanta_power"
HDL_POWER"GND";
"A"15;
%"UNIVERSAL_GND"
"1","(-1750,4025)","0","pure_quanta_power","I71";
;
CDS_LIB"pure_quanta_power"
HDL_POWER"GND";
"A"16;
%"Q_CAP"
"1","(-2875,5500)","0","pure_quanta","I72";
;
LOCATION"PC6546"
$SEC"1"
CDS_SEC"1"
VALUE"10UF"
VOLTAGE"6.3V"
TOLERANCE"20%"
MATERIAL"X6S"
PACK_TYPE"C0402"
CDS_LIB"pure_quanta"
PART_NUMBER"CH6101MEB03";
"B"
$PN"2"20;
"A"
$PN"1"59;
%"Q_CAP"
"1","(-2475,5500)","0","pure_quanta","I73";
;
LOCATION"PC6545"
$SEC"1"
CDS_SEC"1"
VALUE"1UF"
VOLTAGE"16V"
TOLERANCE"10%"
PACK_TYPE"C0402"
MATERIAL"X6S"
CDS_LIB"pure_quanta"
PART_NUMBER"CH5103KEB01";
"B"
$PN"2"20;
"A"
$PN"1"59;
%"Q_CAP"
"1","(-2875,5975)","0","pure_quanta","I74";
;
LOCATION"PC6543"
$SEC"1"
CDS_SEC"1"
PACK_TYPE"C0402"
MATERIAL"X7R"
TOLERANCE"10%"
VOLTAGE"50V"
VALUE"100NF"
CDS_LIB"pure_quanta"
PART_NUMBER"CH4106K1B01";
"B"
$PN"2"30;
"A"
$PN"1"44;
%"Q_CAP"
"1","(-2475,5975)","0","pure_quanta","I75";
;
LOCATION"PC6544"
$SEC"1"
CDS_SEC"1"
VALUE"1UF"
VOLTAGE"16V"
TOLERANCE"10%"
MATERIAL"X6S"
PACK_TYPE"C0402"
CDS_LIB"pure_quanta"
PART_NUMBER"CH5103KEB01";
"B"
$PN"2"30;
"A"
$PN"1"44;
%"VCC15"
"1","(-6700,950)","0","pure_quanta_power","I8";
;
HDL_POWER"P12V_AUX"
CDS_LIB"pure_quanta_power";
"A"31;
%"UNIVERSAL_GND"
"1","(-2025,5300)","3","pure_quanta_power","I80";
;
CDS_LIB"pure_quanta_power"
HDL_POWER"GND";
"A"20;
%"UNIVERSAL_GND"
"1","(-2025,5775)","3","pure_quanta_power","I81";
;
CDS_LIB"pure_quanta_power"
HDL_POWER"GND";
"A"30;
%"Q_RES"
"1","(-2150,6175)","0","pure_quanta","I83";
;
LOCATION"PR6538"
$SEC"1"
CDS_SEC"1"
WATTAGE"1/16W"
VALUE"1"
MATERIAL"CHIP"
PACK_TYPE"0402LF"
TOLERANCE"1%"
CDS_LIB"pure_quanta"
PART_NUMBER"CS-1002FB04";
"B"
$PN"2"29;
"A"
$PN"1"44;
%"VCC15"
"1","(-1675,6300)","0","pure_quanta_power","I84";
;
HDL_POWER"P3V3_AUX"
CDS_LIB"pure_quanta_power";
"A"29;
%"Q_RES"
"2","(-750,1900)","0","pure_quanta","I86";
;
LOCATION"PR6812"
$SEC"1"
CDS_SEC"1"
WATTAGE"1/16W"
MATERIAL"CHIP"
TOLERANCE"1%"
PACK_TYPE"0402LF"
VALUE"1K"
CDS_LIB"pure_quanta"
PART_NUMBER"CS21002FB06";
"A"
$PN"1"17;
"B"
$PN"2"72;
%"VCC15"
"1","(-750,2125)","0","pure_quanta_power","I87";
;
HDL_POWER"P3V3_AUX"
CDS_LIB"pure_quanta_power";
"A"17;
%"ISL69260IRAZT"
"1","(-4125,3425)","0","pure_quanta","I88";
;
LOCATION"PU6510"
SEC"1"
PART_TYPE"SMLF"
VALUE"ISL69260IRAZ-T"
MATERIAL"IC"
CDS_LIB"pure_quanta"
CDS_LMAN_SYM_OUTLINE"-550,2850,500,-2850"
NEEDS_NO_SIZE"TRUE"
SEC_TYPE""
PART_NUMBER"AL069260000";
"CS0"
$PN"30"71;
"PWM0"
$PN"1"70;
"TEMP0"
$PN"35"69;
"ADDR_CFG"
$PN"34"68;
"TH_GND"
$PN"TH"34;
"CFP"
$PN"33"67;
"CS2"
$PN"28"66;
"PWM2"
$PN"3"65;
"CS3"
$PN"27"24;
"PWM3"
$PN"4"64;
"PWM7"
$PN"8"27;
"CS1"
$PN"29"63;
"RGND1"
$PN"31"32;
"VSEN1"
$PN"32"11;
"NPINALERT#||NPSYSCRIT# \B"
$PN"15"23;
"TEMP1||ISYS"
$PN"36"62;
"VINSEN||VSYS"
$PN"38"61;
"VMON||IINSEN||VSYS||ISYS"
$PN"37"60;
"VCCS"
$PN"40"59;
"PWM6"
$PN"7"58;
"PG0"
$PN"12"57;
"PWM1"
$PN"2"56;
"VSEN0"
$PN"21"55;
"PWM5"
$PN"6"26;
"PWM4"
$PN"5"54;
"PMSDA"
$PN"9"42;
"RGND0"
$PN"22"53;
"EN0"
$PN"13"52;
"NPMALERT# \B"
$PN"11"43;
"SVCLK"
$PN"17"51;
"PG1"
$PN"16"50;
"CS4"
$PN"26"25;
"CS5"
$PN"25"49;
"NVRHOT# \B"
$PN"14"48;
"NSVALERT# \B"
$PN"19"47;
"CS6"
$PN"24"21;
"SVDATA"
$PN"18"46;
"PMSCL"
$PN"10"45;
"EN1"
$PN"20"22;
"VCC"
$PN"39"44;
"CS7"
$PN"23"41;
%"Q_RES"
"1","(-6475,4725)","0","pure_quanta","I89";
;
LOCATION"R660"
$SEC"1"
CDS_SEC"1"
TOLERANCE"1%"
VALUE"4.7K"
MATERIAL"EMPTY"
PACK_TYPE"0402LF"
WATTAGE"1/16W"
CDS_LIB"pure_quanta"
PART_NUMBER"CS24702FB06";
"B"
$PN"2"43;
"A"
$PN"1"19;
%"Q_RES"
"2","(-7575,5750)","2","pure_quanta","I90";
;
LOCATION"R6787"
$SEC"1"
CDS_SEC"1"
VALUE"1K"
TOLERANCE"1%"
WATTAGE"1/16W"
PACK_TYPE"0402LF"
MATERIAL"CHIP"
CDS_LIB"pure_quanta"
PART_NUMBER"CS21002FB06";
"A"
$PN"1"52;
"B"
$PN"2"18;
%"UNIVERSAL_GND"
"1","(-7575,5450)","0","pure_quanta_power","I91";
;
CDS_LIB"pure_quanta_power"
HDL_POWER"GND";
"A"18;
%"Q_RES"
"1","(-6325,6325)","0","pure_quanta","I92";
;
LOCATION"R656"
$SEC"1"
CDS_SEC"1"
VALUE"1K"
PACK_TYPE"0402LF"
WATTAGE"1/16W"
MATERIAL"EMPTY"
TOLERANCE"1%"
CDS_LIB"pure_quanta"
PART_NUMBER"CS21002FB06";
"B"
$PN"2"57;
"A"
$PN"1"5;
%"Q_RES"
"1","(-7200,6325)","0","pure_quanta","I93";
;
LOCATION"R6861"
$SEC"1"
CDS_SEC"1"
VALUE"1K"
TOLERANCE"1%"
MATERIAL"CHIP"
WATTAGE"1/16W"
PACK_TYPE"0402LF"
CDS_LIB"pure_quanta"
PART_NUMBER"CS21002FB06";
"B"
$PN"2"57;
"A"
$PN"1"28;
%"VCC15"
"1","(-7575,6450)","0","pure_quanta_power","I94";
;
HDL_POWER"P1V8_AUX"
CDS_LIB"pure_quanta_power";
"A"28;
%"Q_SHORT"
"1","(-7750,4175)","0","pure_quanta","I95";
;
LOCATION"PJ09_P1_P"
$SEC"1"
CDS_SEC"1"
MATERIAL"EMPTY"
PACK_TYPE"SM"
NEEDS_NO_SIZE"TRUE"
CDS_LIB"pure_quanta"
PART_NUMBER"SHORT16";
"1"
$PN"1"40;
"2"
$PN"2"77;
%"Q_SHORT"
"1","(-7750,3800)","0","pure_quanta","I96";
;
LOCATION"PJ09_P1_N"
$SEC"1"
CDS_SEC"1"
MATERIAL"EMPTY"
PACK_TYPE"SM"
NEEDS_NO_SIZE"TRUE"
CDS_LIB"pure_quanta"
PART_NUMBER"SHORT16";
"1"
$PN"1"3;
"2"
$PN"2"53;
END.
